# BASEBOARD_FAB2 (Tioga Pass) — schematic netlist excerpt (pin names and nets, part order shuffled) for the footprints in the layout excerpt that follows; sources: Cadence DE-HDL packaged netlist, KiCad conversion of Wiwynn_Tioga_Pass_MB.brd

R25W8  120R2F-GP  1%  pkg RCL_GP  page 151 : \1\ = GND ; \2\ = BMC_M_WE_N
R9A12  RES  2.21K 1% CHIP  pkg 0402  page 135 : A = FM_PCH_SATA_RAID_KEY_R ; B = P3V3_STBY
C7B27  CAP  0.22UF 16V 10% X7R  pkg 0402  page 129 : A = DMI_CPU0_PCH_TX_DP<2> ; B = DMI_CPU0_PCH_TX_C_DP<2>

(kicad_pcb
	(version 20260206)
	(generator "pcbnew")
	(generator_version "10.0")
	(general
		(thickness 1.6)
		(legacy_teardrops no)
	)
	(paper "A4")
	(title_block
		(title "Wiwynn_Tioga_Pass_MB.brd")
		(comment 1 "Tioga Pass / footprints 1540-1542 of 4770")
	)
	(layers
		(0 "F.Cu" signal "TOP")
		(4 "In1.Cu" signal "L2GND")
		(6 "In2.Cu" signal "L3")
		(8 "In3.Cu" signal "L4GND")
		(10 "In4.Cu" signal "L5")
		(12 "In5.Cu" signal "L6GND")
		(14 "In6.Cu" signal "L7VCC")
		(16 "In7.Cu" signal "L8VCC")
		(18 "In8.Cu" signal "L9GND")
		(20 "In9.Cu" signal "L10")
		(22 "In10.Cu" signal "L11GND")
		(24 "In11.Cu" signal "L12")
		(26 "In12.Cu" signal "L13GND")
		(2 "B.Cu" signal "BOTTOM")
		(9 "F.Adhes" user "F.Adhesive")
		(11 "B.Adhes" user "B.Adhesive")
		(13 "F.Paste" user "Package Geometry/Pastemask Top")
		(15 "B.Paste" user "Package Geometry/Pastemask Bottom")
		(5 "F.SilkS" user "Ref Des/Silkscreen Top")
		(7 "B.SilkS" user "Ref Des/Silkscreen Bottom")
		(1 "F.Mask" user "Board Geometry/Soldermask Top")
		(3 "B.Mask" user "Board Geometry/Soldermask Bottom")
		(17 "Dwgs.User" user "User.Drawings")
		(19 "Cmts.User" user "User.Comments")
		(21 "Eco1.User" user "User.Eco1")
		(23 "Eco2.User" user "User.Eco2")
		(25 "Edge.Cuts" user "Board Geometry/Outline")
		(27 "Margin" user)
		(31 "F.CrtYd" user "Package Geometry/Place Bound Top")
		(29 "B.CrtYd" user "Package Geometry/Place Bound Bottom")
		(35 "F.Fab" user "Ref Des/Assembly Top")
		(33 "B.Fab" user "Ref Des/Assembly Bottom")
	)
	(footprint ""
		(layer "F.Cu")
		(at 473.075 -148.0185 180)
		(property "Reference" "R9A12"
			(at 0 0 180)
			(layer "F.SilkS")
			(hide yes)
			(effects
				(font
					(size 1.27 1.27)
				)
			)
		)
		(property "Value" ""
			(at 0 0 180)
			(layer "F.Fab")
			(effects
				(font
					(size 1.27 1.27)
				)
			)
		)
		(duplicate_pad_numbers_are_jumpers no)
		(fp_poly
			(pts
				(xy -0.2794 -0.1016) (xy 0.2794 -0.1016) (xy 0.2794 0.9906) (xy -0.2794 0.9906)
			)
			(stroke
				(width 0)
				(type default)
			)
			(fill no)
			(layer "F.CrtYd")
		)
		(fp_line
			(start 0.2794 0.9906)
			(end 0.2794 -0.1016)
			(stroke
				(width 0.1)
				(type default)
			)
			(layer "F.Fab")
		)
		(fp_line
			(start 0.2794 -0.1016)
			(end -0.2794 -0.1016)
			(stroke
				(width 0.1)
				(type default)
			)
			(layer "F.Fab")
		)
		(fp_line
			(start -0.2794 0.9906)
			(end 0.2794 0.9906)
			(stroke
				(width 0.1)
				(type default)
			)
			(layer "F.Fab")
		)
		(fp_line
			(start -0.2794 -0.1016)
			(end -0.2794 0.9906)
			(stroke
				(width 0.1)
				(type default)
			)
			(layer "F.Fab")
		)
		(pad "1" smd rect
			(at 0 0 180)
			(size 0.508 0.508)
			(layers "F.Cu" "F.Mask" "F.Paste")
			(net "FM_PCH_SATA_RAID_KEY_R")
		)
		(pad "2" smd rect
			(at 0 0.889 180)
			(size 0.508 0.508)
			(layers "F.Cu" "F.Mask" "F.Paste")
			(net "P3V3_STBY")
		)
		(zone
			(layer "F.Cu")
			(hatch none 0.5)
			(connect_pads
				(clearance 0)
			)
			(min_thickness 0.25)
			(keepout
				(tracks not_allowed)
				(vias allowed)
				(pads allowed)
				(copperpour not_allowed)
				(footprints allowed)
			)
			(placement
				(enabled no)
				(sheetname "")
			)
			(fill
				(thermal_gap 0.5)
				(thermal_bridge_width 0.5)
				(island_removal_mode 0)
			)
			(polygon
				(pts
					(xy 473.329 -148.6535) (xy 472.821 -148.6535) (xy 472.821 -148.2725) (xy 473.329 -148.2725)
				)
			)
		)
		(zone
			(layer "F.Cu")
			(hatch none 0.5)
			(connect_pads
				(clearance 0)
			)
			(min_thickness 0.25)
			(keepout
				(tracks allowed)
				(vias not_allowed)
				(pads allowed)
				(copperpour not_allowed)
				(footprints allowed)
			)
			(placement
				(enabled no)
				(sheetname "")
			)
			(fill
				(thermal_gap 0.5)
				(thermal_bridge_width 0.5)
				(island_removal_mode 0)
			)
			(polygon
				(pts
					(xy 473.329 -148.2725) (xy 472.821 -148.2725) (xy 472.821 -148.6535) (xy 473.329 -148.6535)
				)
			)
		)
	)
	(footprint ""
		(layer "F.Cu")
		(at 449.69938 -31.3055 90)
		(property "Reference" "R25W8"
			(at 0 0 90)
			(layer "F.SilkS")
			(hide yes)
			(effects
				(font
					(size 1.27 1.27)
				)
			)
		)
		(property "Value" "*"
			(at 0.064008 -4.108196 90)
			(unlocked yes)
			(layer "F.Fab")
			(hide yes)
			(effects
				(font
					(size 1.27 1.016)
					(thickness 0.1524)
				)
			)
		)
		(property "Device Type" "120R2F-GP_RCL_GP-120R2F-GP,64.A"
			(at 0.064008 -5.632196 90)
			(unlocked yes)
			(layer "F.Fab")
			(hide yes)
			(effects
				(font
					(size 1.27 1.016)
					(thickness 0.1524)
				)
			)
		)
		(duplicate_pad_numbers_are_jumpers no)
		(fp_line
			(start 0.508 -0.9398)
			(end -0.508 -0.9398)
			(stroke
				(width 0.1524)
				(type default)
			)
			(layer "F.SilkS")
		)
		(fp_line
			(start -0.508 -0.9398)
			(end -0.508 0.9398)
			(stroke
				(width 0.1524)
				(type default)
			)
			(layer "F.SilkS")
		)
		(fp_rect
			(start -0.508 0.9398)
			(end 0.508 -0.9398)
			(stroke
				(width 0)
				(type default)
			)
			(fill no)
			(layer "F.CrtYd")
		)
		(fp_rect
			(start -0.508 0.9398)
			(end 0.508 -0.9398)
			(stroke
				(width 0)
				(type default)
			)
			(fill no)
			(layer "F.Fab")
		)
		(pad "1" smd custom
			(at 0 -0.4445 90)
			(size 0.1397 0.1397)
			(layers "F.Cu" "F.Mask" "F.Paste")
			(net "GND")
			(options
				(clearance outline)
				(anchor circle)
			)
			(primitives
				(gr_poly
					(pts
						(arc
							(start -0.1778 -0.2794)
							(mid -0.249642 -0.249642)
							(end -0.2794 -0.1778)
						)
						(arc
							(start -0.2794 0.1778)
							(mid -0.249642 0.249642)
							(end -0.1778 0.2794)
						)
						(arc
							(start 0.1778 0.2794)
							(mid 0.249642 0.249642)
							(end 0.2794 0.1778)
						)
						(arc
							(start 0.2794 -0.1778)
							(mid 0.249642 -0.249642)
							(end 0.1778 -0.2794)
						)
					)
					(width 0)
					(fill yes)
				)
			)
		)
		(pad "2" smd custom
			(at 0 0.4445 90)
			(size 0.1397 0.1397)
			(layers "F.Cu" "F.Mask" "F.Paste")
			(net "BMC_M_WE_N")
			(options
				(clearance outline)
				(anchor circle)
			)
			(primitives
				(gr_poly
					(pts
						(arc
							(start -0.1778 -0.2794)
							(mid -0.249642 -0.249642)
							(end -0.2794 -0.1778)
						)
						(arc
							(start -0.2794 0.1778)
							(mid -0.249642 0.249642)
							(end -0.1778 0.2794)
						)
						(arc
							(start 0.1778 0.2794)
							(mid 0.249642 0.249642)
							(end 0.2794 0.1778)
						)
						(arc
							(start 0.2794 -0.1778)
							(mid 0.249642 -0.249642)
							(end 0.1778 -0.2794)
						)
					)
					(width 0)
					(fill yes)
				)
			)
		)
	)
	(footprint ""
		(layer "F.Cu")
		(at 368.554 -113.792 90)
		(property "Reference" "C7B27"
			(at 0 0 90)
			(layer "F.SilkS")
			(hide yes)
			(effects
				(font
					(size 1.27 1.27)
				)
			)
		)
		(property "Value" ""
			(at 0 0 90)
			(layer "F.Fab")
			(effects
				(font
					(size 1.27 1.27)
				)
			)
		)
		(duplicate_pad_numbers_are_jumpers no)
		(fp_poly
			(pts
				(xy 0.3048 -0.1016) (xy 0.3048 0.9906) (xy -0.3048 0.9906) (xy -0.3048 -0.1016)
			)
			(stroke
				(width 0)
				(type default)
			)
			(fill no)
			(layer "F.CrtYd")
		)
		(fp_line
			(start 0.3048 -0.1016)
			(end -0.3048 -0.1016)
			(stroke
				(width 0.1)
				(type default)
			)
			(layer "F.Fab")
		)
		(fp_line
			(start -0.3048 -0.1016)
			(end -0.3048 0.9906)
			(stroke
				(width 0.1)
				(type default)
			)
			(layer "F.Fab")
		)
		(fp_line
			(start 0.3048 0.9906)
			(end 0.3048 -0.1016)
			(stroke
				(width 0.1)
				(type default)
			)
			(layer "F.Fab")
		)
		(fp_line
			(start -0.3048 0.9906)
			(end 0.3048 0.9906)
			(stroke
				(width 0.1)
				(type default)
			)
			(layer "F.Fab")
		)
		(pad "1" smd rect
			(at 0 0 90)
			(size 0.508 0.508)
			(layers "F.Cu" "F.Mask" "F.Paste")
			(net "DMI_CPU0_PCH_TX_DP<2>")
		)
		(pad "2" smd rect
			(at 0 0.889 90)
			(size 0.508 0.508)
			(layers "F.Cu" "F.Mask" "F.Paste")
			(net "DMI_CPU0_PCH_TX_C_DP<2>")
		)
		(zone
			(layer "F.Cu")
			(hatch none 0.5)
			(connect_pads
				(clearance 0)
			)
			(min_thickness 0.25)
			(keepout
				(tracks allowed)
				(vias not_allowed)
				(pads allowed)
				(copperpour not_allowed)
				(footprints allowed)
			)
			(placement
				(enabled no)
				(sheetname "")
			)
			(fill
				(thermal_gap 0.5)
				(thermal_bridge_width 0.5)
				(island_removal_mode 0)
			)
			(polygon
				(pts
					(xy 368.808 -113.538) (xy 368.808 -114.046) (xy 369.189 -114.046) (xy 369.189 -113.538)
				)
			)
		)
		(zone
			(layer "F.Cu")
			(hatch none 0.5)
			(connect_pads
				(clearance 0)
			)
			(min_thickness 0.25)
			(keepout
				(tracks not_allowed)
				(vias allowed)
				(pads allowed)
				(copperpour not_allowed)
				(footprints allowed)
			)
			(placement
				(enabled no)
				(sheetname "")
			)
			(fill
				(thermal_gap 0.5)
				(thermal_bridge_width 0.5)
				(island_removal_mode 0)
			)
			(polygon
				(pts
					(xy 369.189 -113.538) (xy 369.189 -114.046) (xy 368.808 -114.046) (xy 368.808 -113.538)
				)
			)
		)
	)
)
